# BASEBOARD_FAB2 (Tioga Pass) — schematic netlist excerpt (pin names and nets, part order shuffled) for the footprints in the layout excerpt that follows; sources: Cadence DE-HDL packaged netlist, KiCad conversion of Wiwynn_Tioga_Pass_MB.brd

C2L15  CAP_A  0.01UF 25V 10% X7R  pkg 0402V  page 173 : A = SATA6G_PCH_PCIE_UP_SATA_RXP<2> ; B = SATA6G_P2_RX_C_DP
R6P3  RES  42.2 1.0% EMPTY  pkg 0402  page 103 : A = CLK_100M_CPU0_RC_REFCLK1_DP ; B = GND
C5G89  CAP_A  22.0UF 4V 20% X6S  pkg 0603V  page 243 : A = PVDDQ_GHJ ; B = GND

(kicad_pcb
	(version 20260206)
	(generator "pcbnew")
	(generator_version "10.0")
	(general
		(thickness 1.6)
		(legacy_teardrops no)
	)
	(paper "A4")
	(title_block
		(title "Wiwynn_Tioga_Pass_MB.brd")
		(comment 1 "Tioga Pass / footprints 3500-3502 of 4770")
	)
	(layers
		(0 "F.Cu" signal "TOP")
		(4 "In1.Cu" signal "L2GND")
		(6 "In2.Cu" signal "L3")
		(8 "In3.Cu" signal "L4GND")
		(10 "In4.Cu" signal "L5")
		(12 "In5.Cu" signal "L6GND")
		(14 "In6.Cu" signal "L7VCC")
		(16 "In7.Cu" signal "L8VCC")
		(18 "In8.Cu" signal "L9GND")
		(20 "In9.Cu" signal "L10")
		(22 "In10.Cu" signal "L11GND")
		(24 "In11.Cu" signal "L12")
		(26 "In12.Cu" signal "L13GND")
		(2 "B.Cu" signal "BOTTOM")
		(9 "F.Adhes" user "F.Adhesive")
		(11 "B.Adhes" user "B.Adhesive")
		(13 "F.Paste" user "Package Geometry/Pastemask Top")
		(15 "B.Paste" user "Package Geometry/Pastemask Bottom")
		(5 "F.SilkS" user "Ref Des/Silkscreen Top")
		(7 "B.SilkS" user "Ref Des/Silkscreen Bottom")
		(1 "F.Mask" user "Board Geometry/Soldermask Top")
		(3 "B.Mask" user "Board Geometry/Soldermask Bottom")
		(17 "Dwgs.User" user "User.Drawings")
		(19 "Cmts.User" user "User.Comments")
		(21 "Eco1.User" user "User.Eco1")
		(23 "Eco2.User" user "User.Eco2")
		(25 "Edge.Cuts" user "Board Geometry/Outline")
		(27 "Margin" user)
		(31 "F.CrtYd" user "Package Geometry/Place Bound Top")
		(29 "B.CrtYd" user "Package Geometry/Place Bound Bottom")
		(35 "F.Fab" user "Ref Des/Assembly Top")
		(33 "B.Fab" user "Ref Des/Assembly Bottom")
	)
	(footprint ""
		(layer "B.Cu")
		(at 171.196 -87.757)
		(property "Reference" "R6P3"
			(at 0 0 0)
			(layer "B.SilkS")
			(hide yes)
			(effects
				(font
					(size 1.27 1.27)
				)
				(justify mirror)
			)
		)
		(property "Value" ""
			(at 0 0 0)
			(layer "B.Fab")
			(effects
				(font
					(size 1.27 1.27)
				)
				(justify mirror)
			)
		)
		(duplicate_pad_numbers_are_jumpers no)
		(fp_poly
			(pts
				(xy 0.2794 -0.1016) (xy -0.2794 -0.1016) (xy -0.2794 0.9906) (xy 0.2794 0.9906)
			)
			(stroke
				(width 0)
				(type default)
			)
			(fill no)
			(layer "B.CrtYd")
		)
		(fp_line
			(start -0.2794 -0.1016)
			(end 0.2794 -0.1016)
			(stroke
				(width 0.1)
				(type default)
			)
			(layer "B.Fab")
		)
		(fp_line
			(start -0.2794 0.9906)
			(end -0.2794 -0.1016)
			(stroke
				(width 0.1)
				(type default)
			)
			(layer "B.Fab")
		)
		(fp_line
			(start 0.2794 -0.1016)
			(end 0.2794 0.9906)
			(stroke
				(width 0.1)
				(type default)
			)
			(layer "B.Fab")
		)
		(fp_line
			(start 0.2794 0.9906)
			(end -0.2794 0.9906)
			(stroke
				(width 0.1)
				(type default)
			)
			(layer "B.Fab")
		)
		(pad "1" smd rect
			(at 0 0 180)
			(size 0.508 0.508)
			(layers "B.Cu" "B.Mask" "B.Paste")
			(net "CLK_100M_CPU0_RC_REFCLK1_DP")
		)
		(pad "2" smd rect
			(at 0 0.889 180)
			(size 0.508 0.508)
			(layers "B.Cu" "B.Mask" "B.Paste")
			(net "GND")
		)
		(zone
			(layer "B.Cu")
			(hatch none 0.5)
			(connect_pads
				(clearance 0)
			)
			(min_thickness 0.25)
			(keepout
				(tracks allowed)
				(vias not_allowed)
				(pads allowed)
				(copperpour not_allowed)
				(footprints allowed)
			)
			(placement
				(enabled no)
				(sheetname "")
			)
			(fill
				(thermal_gap 0.5)
				(thermal_bridge_width 0.5)
				(island_removal_mode 0)
			)
			(polygon
				(pts
					(xy 171.45 -87.503) (xy 170.942 -87.503) (xy 170.942 -87.122) (xy 171.45 -87.122)
				)
			)
		)
		(zone
			(layer "B.Cu")
			(hatch none 0.5)
			(connect_pads
				(clearance 0)
			)
			(min_thickness 0.25)
			(keepout
				(tracks not_allowed)
				(vias allowed)
				(pads allowed)
				(copperpour not_allowed)
				(footprints allowed)
			)
			(placement
				(enabled no)
				(sheetname "")
			)
			(fill
				(thermal_gap 0.5)
				(thermal_bridge_width 0.5)
				(island_removal_mode 0)
			)
			(polygon
				(pts
					(xy 171.45 -87.122) (xy 170.942 -87.122) (xy 170.942 -87.503) (xy 171.45 -87.503)
				)
			)
		)
	)
	(footprint ""
		(layer "B.Cu")
		(at 420.624 -150.876 90)
		(property "Reference" "C2L15"
			(at 0 0 90)
			(layer "B.SilkS")
			(hide yes)
			(effects
				(font
					(size 1.27 1.27)
				)
				(justify mirror)
			)
		)
		(property "Value" ""
			(at 0 0 90)
			(layer "B.Fab")
			(effects
				(font
					(size 1.27 1.27)
				)
				(justify mirror)
			)
		)
		(duplicate_pad_numbers_are_jumpers no)
		(fp_poly
			(pts
				(xy -0.3048 -0.1016) (xy -0.3048 0.9906) (xy 0.3048 0.9906) (xy 0.3048 -0.1016)
			)
			(stroke
				(width 0)
				(type default)
			)
			(fill no)
			(layer "B.CrtYd")
		)
		(fp_line
			(start 0.3048 -0.1016)
			(end 0.3048 0.9906)
			(stroke
				(width 0.1)
				(type default)
			)
			(layer "B.Fab")
		)
		(fp_line
			(start -0.3048 -0.1016)
			(end 0.3048 -0.1016)
			(stroke
				(width 0.1)
				(type default)
			)
			(layer "B.Fab")
		)
		(fp_line
			(start 0.3048 0.9906)
			(end -0.3048 0.9906)
			(stroke
				(width 0.1)
				(type default)
			)
			(layer "B.Fab")
		)
		(fp_line
			(start -0.3048 0.9906)
			(end -0.3048 -0.1016)
			(stroke
				(width 0.1)
				(type default)
			)
			(layer "B.Fab")
		)
		(pad "1" smd rect
			(at 0 0 270)
			(size 0.508 0.508)
			(layers "B.Cu" "B.Mask" "B.Paste")
			(net "SATA6G_PCH_PCIE_UP_SATA_RXP<2>")
		)
		(pad "2" smd rect
			(at 0 0.889 270)
			(size 0.508 0.508)
			(layers "B.Cu" "B.Mask" "B.Paste")
			(net "SATA6G_P2_RX_C_DP")
		)
		(zone
			(layer "B.Cu")
			(hatch none 0.5)
			(connect_pads
				(clearance 0)
			)
			(min_thickness 0.25)
			(keepout
				(tracks allowed)
				(vias not_allowed)
				(pads allowed)
				(copperpour not_allowed)
				(footprints allowed)
			)
			(placement
				(enabled no)
				(sheetname "")
			)
			(fill
				(thermal_gap 0.5)
				(thermal_bridge_width 0.5)
				(island_removal_mode 0)
			)
			(polygon
				(pts
					(xy 420.878 -151.13) (xy 420.878 -150.622) (xy 421.259 -150.622) (xy 421.259 -151.13)
				)
			)
		)
		(zone
			(layer "B.Cu")
			(hatch none 0.5)
			(connect_pads
				(clearance 0)
			)
			(min_thickness 0.25)
			(keepout
				(tracks not_allowed)
				(vias allowed)
				(pads allowed)
				(copperpour not_allowed)
				(footprints allowed)
			)
			(placement
				(enabled no)
				(sheetname "")
			)
			(fill
				(thermal_gap 0.5)
				(thermal_bridge_width 0.5)
				(island_removal_mode 0)
			)
			(polygon
				(pts
					(xy 421.259 -151.13) (xy 421.259 -150.622) (xy 420.878 -150.622) (xy 420.878 -151.13)
				)
			)
		)
	)
	(footprint ""
		(layer "B.Cu")
		(at 101.3968 -3.3528 90)
		(property "Reference" "C5G89"
			(at -1.14681 0.76708 180)
			(unlocked yes)
			(layer "B.SilkS")
			(effects
				(font
					(size 0.7874 0.5842)
					(thickness 0.1524)
				)
				(justify mirror)
			)
		)
		(property "Value" ""
			(at 0 0 90)
			(layer "B.Fab")
			(effects
				(font
					(size 1.27 1.27)
				)
				(justify mirror)
			)
		)
		(duplicate_pad_numbers_are_jumpers no)
		(fp_rect
			(start -0.4953 -0.2032)
			(end 0.4953 1.6002)
			(stroke
				(width 0)
				(type default)
			)
			(fill no)
			(layer "B.CrtYd")
		)
		(fp_line
			(start 0.4953 -0.2032)
			(end -0.4953 -0.2032)
			(stroke
				(width 0.1)
				(type default)
			)
			(layer "B.Fab")
		)
		(fp_line
			(start -0.4953 -0.2032)
			(end -0.4953 1.6002)
			(stroke
				(width 0.1)
				(type default)
			)
			(layer "B.Fab")
		)
		(fp_line
			(start 0.4953 1.6002)
			(end 0.4953 -0.2032)
			(stroke
				(width 0.1)
				(type default)
			)
			(layer "B.Fab")
		)
		(fp_line
			(start -0.4953 1.6002)
			(end 0.4953 1.6002)
			(stroke
				(width 0.1)
				(type default)
			)
			(layer "B.Fab")
		)
		(pad "1" smd rect
			(at 0 0 270)
			(size 0.762 0.889)
			(layers "B.Cu" "B.Mask" "B.Paste")
			(net "PVDDQ_GHJ")
		)
		(pad "2" smd rect
			(at 0 1.397 270)
			(size 0.762 0.889)
			(layers "B.Cu" "B.Mask" "B.Paste")
			(net "GND")
		)
		(zone
			(layer "B.Cu")
			(hatch none 0.5)
			(connect_pads
				(clearance 0)
			)
			(min_thickness 0.25)
			(keepout
				(tracks not_allowed)
				(vias allowed)
				(pads allowed)
				(copperpour not_allowed)
				(footprints allowed)
			)
			(placement
				(enabled no)
				(sheetname "")
			)
			(fill
				(thermal_gap 0.5)
				(thermal_bridge_width 0.5)
				(island_removal_mode 0)
			)
			(polygon
				(pts
					(xy 101.8413 -2.9718) (xy 102.3493 -2.9718) (xy 102.3493 -3.7338) (xy 101.8413 -3.7338)
				)
			)
		)
	)
)
